(kicad_pcb
	(version 20260206)
	(generator "pcbnew")
	(generator_version "10.0")
	(general
		(thickness 1.6)
		(legacy_teardrops no)
	)
	(paper "A4")
	(title_block
		(title "netronome-mezz — pcbd0082-001_rev01_jul9_a.brd")
		(comment 1 "Open CloudServer (Microsoft) / footprints 379-387 of 714")
	)
	(layers
		(0 "F.Cu" signal "TOP")
		(4 "In1.Cu" signal "02_GND")
		(6 "In2.Cu" signal "03_SIG")
		(8 "In3.Cu" signal "04_SIG")
		(10 "In4.Cu" signal "05_GND")
		(12 "In5.Cu" signal "06_PWR1")
		(14 "In6.Cu" signal "07_SIG")
		(16 "In7.Cu" signal "08_SIG")
		(18 "In8.Cu" signal "09_GND")
		(2 "B.Cu" signal "BOTTOM")
		(9 "F.Adhes" user "F.Adhesive")
		(11 "B.Adhes" user "B.Adhesive")
		(13 "F.Paste" user "Package Geometry/Pastemask Top")
		(15 "B.Paste" user "Package Geometry/Pastemask Bottom")
		(5 "F.SilkS" user "Ref Des/Silkscreen Top")
		(7 "B.SilkS" user "Ref Des/Silkscreen Bottom")
		(1 "F.Mask" user "Board Geometry/Soldermask Top")
		(3 "B.Mask" user "Board Geometry/Soldermask Bottom")
		(17 "Dwgs.User" user "User.Drawings")
		(19 "Cmts.User" user "User.Comments")
		(21 "Eco1.User" user "User.Eco1")
		(23 "Eco2.User" user "User.Eco2")
		(25 "Edge.Cuts" user "Board Geometry/Outline")
		(27 "Margin" user)
		(31 "F.CrtYd" user "Package Geometry/Place Bound Top")
		(29 "B.CrtYd" user "Package Geometry/Place Bound Bottom")
		(35 "F.Fab" user "Ref Des/Assembly Top")
		(33 "B.Fab" user "Ref Des/Assembly Bottom")
		(45 "User.4" user "COMPVAL_TYPE_BOTTOM")
	)
	(footprint ""
		(layer "B.Cu")
		(at 62.484 3.556 90)
		(property "Reference" "C279"
			(at 0.98933 0.762 0)
			(unlocked yes)
			(layer "B.SilkS")
			(effects
				(font
					(size 0.7874 0.5842)
					(thickness 0.127)
				)
				(justify left mirror)
			)
		)
		(property "Value" "22UF"
			(at 0.148158 1.7526 0)
			(unlocked yes)
			(layer "B.Fab")
			(hide yes)
			(effects
				(font
					(size 1.27 0.9652)
					(thickness 0.000001)
				)
				(justify left mirror)
			)
		)
		(property "Device Type" "CAPC0063"
			(at 0.148158 1.7526 0)
			(unlocked yes)
			(layer "B.Fab")
			(hide yes)
			(effects
				(font
					(size 1.27 0.9652)
					(thickness 0.000001)
				)
				(justify left mirror)
			)
		)
		(duplicate_pad_numbers_are_jumpers no)
		(fp_circle
			(center 0 0)
			(end 0 0.127)
			(stroke
				(width 0.2032)
				(type default)
			)
			(fill no)
			(layer "B.SilkS")
		)
		(fp_poly
			(pts
				(xy -0.7874 -1.6637) (xy 0.7874 -1.6637) (xy 0.7874 1.6637) (xy -0.7874 1.6637)
			)
			(stroke
				(width 0)
				(type default)
			)
			(fill no)
			(layer "B.CrtYd")
		)
		(fp_line
			(start 0.4064 -0.7874)
			(end -0.4064 -0.7874)
			(stroke
				(width 0.0254)
				(type default)
			)
			(layer "B.Fab")
		)
		(fp_line
			(start -0.4064 -0.7874)
			(end -0.4064 0.8128)
			(stroke
				(width 0.0254)
				(type default)
			)
			(layer "B.Fab")
		)
		(fp_line
			(start 0.4064 0.8128)
			(end 0.4064 -0.7874)
			(stroke
				(width 0.0254)
				(type default)
			)
			(layer "B.Fab")
		)
		(fp_line
			(start -0.4064 0.8128)
			(end 0.4064 0.8128)
			(stroke
				(width 0.0254)
				(type default)
			)
			(layer "B.Fab")
		)
		(pad "1" smd rect
			(at 0 -0.8001 270)
			(size 0.8636 0.9652)
			(layers "B.Cu" "B.Mask" "B.Paste")
			(net "VDDA_PCIE0")
		)
		(pad "2" smd rect
			(at 0 0.8001 270)
			(size 0.8636 0.9652)
			(layers "B.Cu" "B.Mask" "B.Paste")
			(net "GND")
		)
		(zone
			(layer "B.Cu")
			(hatch none 0.5)
			(connect_pads
				(clearance 0)
			)
			(min_thickness 0.25)
			(keepout
				(tracks not_allowed)
				(vias allowed)
				(pads allowed)
				(copperpour not_allowed)
				(footprints allowed)
			)
			(placement
				(enabled no)
				(sheetname "")
			)
			(fill
				(thermal_gap 0.5)
				(thermal_bridge_width 0.5)
				(island_removal_mode 0)
			)
			(polygon
				(pts
					(xy 62.23 3.4925) (xy 62.23 3.6195) (xy 62.738 3.6195) (xy 62.738 3.4925)
				)
			)
		)
	)
	(footprint ""
		(layer "B.Cu")
		(at 40.259 9.652 -90)
		(property "Reference" "R405"
			(at -0.73533 -0.762 0)
			(unlocked yes)
			(layer "B.SilkS")
			(effects
				(font
					(size 0.7874 0.5842)
					(thickness 0.127)
				)
				(justify left mirror)
			)
		)
		(property "Value" "4.75K"
			(at 0.148158 1.3462 180)
			(unlocked yes)
			(layer "B.Fab")
			(hide yes)
			(effects
				(font
					(size 1.27 0.9652)
					(thickness 0.000001)
				)
				(justify left mirror)
			)
		)
		(property "Device Type" "REST4024"
			(at 0.148158 1.3462 180)
			(unlocked yes)
			(layer "B.Fab")
			(hide yes)
			(effects
				(font
					(size 1.27 0.9652)
					(thickness 0.000001)
				)
				(justify left mirror)
			)
		)
		(duplicate_pad_numbers_are_jumpers no)
		(fp_poly
			(pts
				(xy -0.635 1.0668) (xy -0.635 -1.0668) (xy 0.635 -1.0668) (xy 0.635 1.0668)
			)
			(stroke
				(width 0)
				(type default)
			)
			(fill no)
			(layer "B.CrtYd")
		)
		(fp_line
			(start -0.254 0.508)
			(end 0.254 0.508)
			(stroke
				(width 0.0254)
				(type default)
			)
			(layer "B.Fab")
		)
		(fp_line
			(start 0.254 0.508)
			(end 0.254 -0.508)
			(stroke
				(width 0.0254)
				(type default)
			)
			(layer "B.Fab")
		)
		(fp_line
			(start -0.254 -0.508)
			(end -0.254 0.508)
			(stroke
				(width 0.0254)
				(type default)
			)
			(layer "B.Fab")
		)
		(fp_line
			(start 0.254 -0.508)
			(end -0.254 -0.508)
			(stroke
				(width 0.0254)
				(type default)
			)
			(layer "B.Fab")
		)
		(pad "1" smd rect
			(at 0 -0.4191 90)
			(size 0.508 0.5334)
			(layers "B.Cu" "B.Mask" "B.Paste")
			(net "VDD_3.3V")
		)
		(pad "2" smd rect
			(at 0 0.4191 90)
			(size 0.508 0.5334)
			(layers "B.Cu" "B.Mask" "B.Paste")
			(net "NFP_JTAG_ARM_TMS")
		)
		(zone
			(layer "B.Cu")
			(hatch none 0.5)
			(connect_pads
				(clearance 0)
			)
			(min_thickness 0.25)
			(keepout
				(tracks not_allowed)
				(vias allowed)
				(pads allowed)
				(copperpour not_allowed)
				(footprints allowed)
			)
			(placement
				(enabled no)
				(sheetname "")
			)
			(fill
				(thermal_gap 0.5)
				(thermal_bridge_width 0.5)
				(island_removal_mode 0)
			)
			(polygon
				(pts
					(xy 40.2844 9.6266) (xy 40.2336 9.6266) (xy 40.2336 9.6774) (xy 40.2844 9.6774)
				)
			)
		)
	)
	(footprint ""
		(layer "B.Cu")
		(at 44.73702 13.042011 90)
		(property "Reference" "C275"
			(at 0 0 90)
			(layer "B.SilkS")
			(hide yes)
			(effects
				(font
					(size 1.27 1.27)
				)
				(justify mirror)
			)
		)
		(property "Value" ""
			(at 0 0 90)
			(layer "B.Fab")
			(effects
				(font
					(size 1.27 1.27)
				)
				(justify mirror)
			)
		)
		(duplicate_pad_numbers_are_jumpers no)
		(fp_circle
			(center 0 0)
			(end 0 0.104648)
			(stroke
				(width 0.1016)
				(type default)
			)
			(fill no)
			(layer "B.SilkS")
		)
		(fp_poly
			(pts
				(xy 0.381 -0.889) (xy 0.381 0.889) (xy -0.381 0.889) (xy -0.381 -0.889)
			)
			(stroke
				(width 0)
				(type default)
			)
			(fill no)
			(layer "B.CrtYd")
		)
		(fp_line
			(start 0.508 -1.016)
			(end 0.254 -1.016)
			(stroke
				(width 0.0254)
				(type default)
			)
			(layer "B.Fab")
		)
		(fp_line
			(start 0.254 -1.016)
			(end -0.508 -1.016)
			(stroke
				(width 0.0254)
				(type default)
			)
			(layer "B.Fab")
		)
		(fp_line
			(start -0.508 -1.016)
			(end -0.508 1.016)
			(stroke
				(width 0.0254)
				(type default)
			)
			(layer "B.Fab")
		)
		(fp_line
			(start 0.508 1.016)
			(end 0.508 -1.016)
			(stroke
				(width 0.0254)
				(type default)
			)
			(layer "B.Fab")
		)
		(fp_line
			(start -0.508 1.016)
			(end 0.508 1.016)
			(stroke
				(width 0.0254)
				(type default)
			)
			(layer "B.Fab")
		)
		(pad "1" smd custom
			(at 0 -0.500126 270)
			(size 0.127 0.127)
			(layers "B.Cu" "B.Mask" "B.Paste")
			(net "VDD_3.3V")
			(options
				(clearance outline)
				(anchor circle)
			)
			(primitives
				(gr_poly
					(pts
						(xy -0.1778 0.254) (xy 0.1778 0.254) (xy 0.254 0.1778) (xy 0.254 -0.1778) (xy 0.1778 -0.254) (xy -0.1778 -0.254)
						(xy -0.254 -0.1778) (xy -0.254 0.1778)
					)
					(width 0)
					(fill yes)
				)
			)
		)
		(pad "2" smd custom
			(at 0 0.500126 270)
			(size 0.127 0.127)
			(layers "B.Cu" "B.Mask" "B.Paste")
			(net "GND")
			(options
				(clearance outline)
				(anchor circle)
			)
			(primitives
				(gr_poly
					(pts
						(xy -0.1778 0.254) (xy 0.1778 0.254) (xy 0.254 0.1778) (xy 0.254 -0.1778) (xy 0.1778 -0.254) (xy -0.1778 -0.254)
						(xy -0.254 -0.1778) (xy -0.254 0.1778)
					)
					(width 0)
					(fill yes)
				)
			)
		)
	)
	(footprint ""
		(layer "B.Cu")
		(at 61.737011 9.042019 90)
		(property "Reference" "C170"
			(at 0 0 90)
			(layer "B.SilkS")
			(hide yes)
			(effects
				(font
					(size 1.27 1.27)
				)
				(justify mirror)
			)
		)
		(property "Value" ""
			(at 0 0 90)
			(layer "B.Fab")
			(effects
				(font
					(size 1.27 1.27)
				)
				(justify mirror)
			)
		)
		(duplicate_pad_numbers_are_jumpers no)
		(fp_circle
			(center 0 0)
			(end 0 0.104648)
			(stroke
				(width 0.1016)
				(type default)
			)
			(fill no)
			(layer "B.SilkS")
		)
		(fp_poly
			(pts
				(xy 0.381 -0.889) (xy 0.381 0.889) (xy -0.381 0.889) (xy -0.381 -0.889)
			)
			(stroke
				(width 0)
				(type default)
			)
			(fill no)
			(layer "B.CrtYd")
		)
		(fp_line
			(start 0.508 -1.016)
			(end 0.254 -1.016)
			(stroke
				(width 0.0254)
				(type default)
			)
			(layer "B.Fab")
		)
		(fp_line
			(start 0.254 -1.016)
			(end -0.508 -1.016)
			(stroke
				(width 0.0254)
				(type default)
			)
			(layer "B.Fab")
		)
		(fp_line
			(start -0.508 -1.016)
			(end -0.508 1.016)
			(stroke
				(width 0.0254)
				(type default)
			)
			(layer "B.Fab")
		)
		(fp_line
			(start 0.508 1.016)
			(end 0.508 -1.016)
			(stroke
				(width 0.0254)
				(type default)
			)
			(layer "B.Fab")
		)
		(fp_line
			(start -0.508 1.016)
			(end 0.508 1.016)
			(stroke
				(width 0.0254)
				(type default)
			)
			(layer "B.Fab")
		)
		(pad "1" smd custom
			(at 0 -0.500126 270)
			(size 0.127 0.127)
			(layers "B.Cu" "B.Mask" "B.Paste")
			(net "VDDA_PCIE0")
			(options
				(clearance outline)
				(anchor circle)
			)
			(primitives
				(gr_poly
					(pts
						(xy -0.1778 0.254) (xy 0.1778 0.254) (xy 0.254 0.1778) (xy 0.254 -0.1778) (xy 0.1778 -0.254) (xy -0.1778 -0.254)
						(xy -0.254 -0.1778) (xy -0.254 0.1778)
					)
					(width 0)
					(fill yes)
				)
			)
		)
		(pad "2" smd custom
			(at 0 0.500126 270)
			(size 0.127 0.127)
			(layers "B.Cu" "B.Mask" "B.Paste")
			(net "GND")
			(options
				(clearance outline)
				(anchor circle)
			)
			(primitives
				(gr_poly
					(pts
						(xy -0.1778 0.254) (xy 0.1778 0.254) (xy 0.254 0.1778) (xy 0.254 -0.1778) (xy 0.1778 -0.254) (xy -0.1778 -0.254)
						(xy -0.254 -0.1778) (xy -0.254 0.1778)
					)
					(width 0)
					(fill yes)
				)
			)
		)
	)
	(footprint ""
		(layer "B.Cu")
		(at 84.250987 6.698996)
		(property "Reference" "V1_A-A14"
			(at 0 0 0)
			(layer "B.SilkS")
			(hide yes)
			(effects
				(font
					(size 1.27 1.27)
				)
				(justify mirror)
			)
		)
		(property "Value" ""
			(at 0 0 0)
			(layer "B.Fab")
			(effects
				(font
					(size 1.27 1.27)
				)
				(justify mirror)
			)
		)
		(duplicate_pad_numbers_are_jumpers no)
		(pad "1" thru_hole circle
			(at 0 0 180)
			(size 0.4572 0.4572)
			(drill 0.20574)
			(layers "*.Cu" "*.Mask")
			(remove_unused_layers no)
			(net "DDR0_32A_A14")
			(clearance 0.1143)
			(thermal_gap 0.1143)
		)
	)
	(footprint ""
		(layer "B.Cu")
		(at 69.236971 13.54201 180)
		(property "Reference" "C192"
			(at 0 0 0)
			(layer "B.SilkS")
			(hide yes)
			(effects
				(font
					(size 1.27 1.27)
				)
				(justify mirror)
			)
		)
		(property "Value" ""
			(at 0 0 0)
			(layer "B.Fab")
			(effects
				(font
					(size 1.27 1.27)
				)
				(justify mirror)
			)
		)
		(duplicate_pad_numbers_are_jumpers no)
		(fp_circle
			(center 0 0)
			(end -0.104648 0)
			(stroke
				(width 0.1016)
				(type default)
			)
			(fill no)
			(layer "B.SilkS")
		)
		(fp_poly
			(pts
				(xy 0.381 -0.889) (xy 0.381 0.889) (xy -0.381 0.889) (xy -0.381 -0.889)
			)
			(stroke
				(width 0)
				(type default)
			)
			(fill no)
			(layer "B.CrtYd")
		)
		(fp_line
			(start 0.508 1.016)
			(end 0.508 -1.016)
			(stroke
				(width 0.0254)
				(type default)
			)
			(layer "B.Fab")
		)
		(fp_line
			(start 0.508 -1.016)
			(end 0.254 -1.016)
			(stroke
				(width 0.0254)
				(type default)
			)
			(layer "B.Fab")
		)
		(fp_line
			(start 0.254 -1.016)
			(end -0.508 -1.016)
			(stroke
				(width 0.0254)
				(type default)
			)
			(layer "B.Fab")
		)
		(fp_line
			(start -0.508 1.016)
			(end 0.508 1.016)
			(stroke
				(width 0.0254)
				(type default)
			)
			(layer "B.Fab")
		)
		(fp_line
			(start -0.508 -1.016)
			(end -0.508 1.016)
			(stroke
				(width 0.0254)
				(type default)
			)
			(layer "B.Fab")
		)
		(pad "1" smd custom
			(at 0 -0.500126)
			(size 0.127 0.127)
			(layers "B.Cu" "B.Mask" "B.Paste")
			(net "DDR_VDDQ")
			(options
				(clearance outline)
				(anchor circle)
			)
			(primitives
				(gr_poly
					(pts
						(xy -0.1778 0.254) (xy 0.1778 0.254) (xy 0.254 0.1778) (xy 0.254 -0.1778) (xy 0.1778 -0.254) (xy -0.1778 -0.254)
						(xy -0.254 -0.1778) (xy -0.254 0.1778)
					)
					(width 0)
					(fill yes)
				)
			)
		)
		(pad "2" smd custom
			(at 0 0.500126)
			(size 0.127 0.127)
			(layers "B.Cu" "B.Mask" "B.Paste")
			(net "GND")
			(options
				(clearance outline)
				(anchor circle)
			)
			(primitives
				(gr_poly
					(pts
						(xy -0.1778 0.254) (xy 0.1778 0.254) (xy 0.254 0.1778) (xy 0.254 -0.1778) (xy 0.1778 -0.254) (xy -0.1778 -0.254)
						(xy -0.254 -0.1778) (xy -0.254 0.1778)
					)
					(width 0)
					(fill yes)
				)
			)
		)
	)
	(footprint ""
		(layer "B.Cu")
		(at 43.237023 18.542)
		(property "Reference" "C273"
			(at 0 0 0)
			(layer "B.SilkS")
			(hide yes)
			(effects
				(font
					(size 1.27 1.27)
				)
				(justify mirror)
			)
		)
		(property "Value" ""
			(at 0 0 0)
			(layer "B.Fab")
			(effects
				(font
					(size 1.27 1.27)
				)
				(justify mirror)
			)
		)
		(duplicate_pad_numbers_are_jumpers no)
		(fp_circle
			(center 0 0)
			(end 0.104648 0)
			(stroke
				(width 0.1016)
				(type default)
			)
			(fill no)
			(layer "B.SilkS")
		)
		(fp_poly
			(pts
				(xy 0.381 -0.889) (xy 0.381 0.889) (xy -0.381 0.889) (xy -0.381 -0.889)
			)
			(stroke
				(width 0)
				(type default)
			)
			(fill no)
			(layer "B.CrtYd")
		)
		(fp_line
			(start -0.508 -1.016)
			(end -0.508 1.016)
			(stroke
				(width 0.0254)
				(type default)
			)
			(layer "B.Fab")
		)
		(fp_line
			(start -0.508 1.016)
			(end 0.508 1.016)
			(stroke
				(width 0.0254)
				(type default)
			)
			(layer "B.Fab")
		)
		(fp_line
			(start 0.254 -1.016)
			(end -0.508 -1.016)
			(stroke
				(width 0.0254)
				(type default)
			)
			(layer "B.Fab")
		)
		(fp_line
			(start 0.508 -1.016)
			(end 0.254 -1.016)
			(stroke
				(width 0.0254)
				(type default)
			)
			(layer "B.Fab")
		)
		(fp_line
			(start 0.508 1.016)
			(end 0.508 -1.016)
			(stroke
				(width 0.0254)
				(type default)
			)
			(layer "B.Fab")
		)
		(pad "1" smd custom
			(at 0 -0.500126 180)
			(size 0.127 0.127)
			(layers "B.Cu" "B.Mask" "B.Paste")
			(net "VDD_1.8V")
			(options
				(clearance outline)
				(anchor circle)
			)
			(primitives
				(gr_poly
					(pts
						(xy -0.1778 0.254) (xy 0.1778 0.254) (xy 0.254 0.1778) (xy 0.254 -0.1778) (xy 0.1778 -0.254) (xy -0.1778 -0.254)
						(xy -0.254 -0.1778) (xy -0.254 0.1778)
					)
					(width 0)
					(fill yes)
				)
			)
		)
		(pad "2" smd custom
			(at 0 0.500126 180)
			(size 0.127 0.127)
			(layers "B.Cu" "B.Mask" "B.Paste")
			(net "GND")
			(options
				(clearance outline)
				(anchor circle)
			)
			(primitives
				(gr_poly
					(pts
						(xy -0.1778 0.254) (xy 0.1778 0.254) (xy 0.254 0.1778) (xy 0.254 -0.1778) (xy 0.1778 -0.254) (xy -0.1778 -0.254)
						(xy -0.254 -0.1778) (xy -0.254 0.1778)
					)
					(width 0)
					(fill yes)
				)
			)
		)
	)
	(footprint ""
		(layer "B.Cu")
		(at 72.251011 5.898998)
		(property "Reference" "V_A-DQ13"
			(at 0 0 0)
			(layer "B.SilkS")
			(hide yes)
			(effects
				(font
					(size 1.27 1.27)
				)
				(justify mirror)
			)
		)
		(property "Value" ""
			(at 0 0 0)
			(layer "B.Fab")
			(effects
				(font
					(size 1.27 1.27)
				)
				(justify mirror)
			)
		)
		(duplicate_pad_numbers_are_jumpers no)
		(pad "1" thru_hole circle
			(at 0 0 180)
			(size 0.4572 0.4572)
			(drill 0.20574)
			(layers "*.Cu" "*.Mask")
			(remove_unused_layers no)
			(net "DDR0_32A_DQ13")
			(clearance 0.1143)
			(thermal_gap 0.1143)
		)
	)
	(footprint ""
		(layer "B.Cu")
		(at 60.736988 12.042013 90)
		(property "Reference" "R144"
			(at 0 0 90)
			(layer "B.SilkS")
			(hide yes)
			(effects
				(font
					(size 1.27 1.27)
				)
				(justify mirror)
			)
		)
		(property "Value" ""
			(at 0 0 90)
			(layer "B.Fab")
			(effects
				(font
					(size 1.27 1.27)
				)
				(justify mirror)
			)
		)
		(duplicate_pad_numbers_are_jumpers no)
		(fp_circle
			(center 0 0)
			(end 0 0.104648)
			(stroke
				(width 0.1016)
				(type default)
			)
			(fill no)
			(layer "B.SilkS")
		)
		(fp_poly
			(pts
				(xy 0.381 -0.889) (xy 0.381 0.889) (xy -0.381 0.889) (xy -0.381 -0.889)
			)
			(stroke
				(width 0)
				(type default)
			)
			(fill no)
			(layer "B.CrtYd")
		)
		(fp_line
			(start 0.508 -1.016)
			(end 0.254 -1.016)
			(stroke
				(width 0.0254)
				(type default)
			)
			(layer "B.Fab")
		)
		(fp_line
			(start 0.254 -1.016)
			(end -0.508 -1.016)
			(stroke
				(width 0.0254)
				(type default)
			)
			(layer "B.Fab")
		)
		(fp_line
			(start -0.508 -1.016)
			(end -0.508 1.016)
			(stroke
				(width 0.0254)
				(type default)
			)
			(layer "B.Fab")
		)
		(fp_line
			(start 0.508 1.016)
			(end 0.508 -1.016)
			(stroke
				(width 0.0254)
				(type default)
			)
			(layer "B.Fab")
		)
		(fp_line
			(start -0.508 1.016)
			(end 0.508 1.016)
			(stroke
				(width 0.0254)
				(type default)
			)
			(layer "B.Fab")
		)
		(pad "1" smd custom
			(at 0 -0.500126 270)
			(size 0.127 0.127)
			(layers "B.Cu" "B.Mask" "B.Paste")
			(net "VDD_CORE")
			(options
				(clearance outline)
				(anchor circle)
			)
			(primitives
				(gr_poly
					(pts
						(xy -0.1778 0.254) (xy 0.1778 0.254) (xy 0.254 0.1778) (xy 0.254 -0.1778) (xy 0.1778 -0.254) (xy -0.1778 -0.254)
						(xy -0.254 -0.1778) (xy -0.254 0.1778)
					)
					(width 0)
					(fill yes)
				)
			)
		)
		(pad "2" smd custom
			(at 0 0.500126 270)
			(size 0.127 0.127)
			(layers "B.Cu" "B.Mask" "B.Paste")
			(net "VDDA_DDR0_32A")
			(options
				(clearance outline)
				(anchor circle)
			)
			(primitives
				(gr_poly
					(pts
						(xy -0.1778 0.254) (xy 0.1778 0.254) (xy 0.254 0.1778) (xy 0.254 -0.1778) (xy 0.1778 -0.254) (xy -0.1778 -0.254)
						(xy -0.254 -0.1778) (xy -0.254 0.1778)
					)
					(width 0)
					(fill yes)
				)
			)
		)
	)
)
